FILE_TYPE=LIBRARY_PARTS;
primitive '3D01R5F-GP_SMD-RG5';
  pin
    '1':
      PIN_NUMBER='(1)';
      PIN_TYPE='ANALOG';
      NO_LOAD_CHECK='Both';
      NO_IO_CHECK='Both';
      NO_ASSERT_CHECK='TRUE';
      NO_DIR_CHECK='TRUE';
      ALLOW_CONNECT='TRUE';
    '2':
      PIN_NUMBER='(2)';
      PIN_TYPE='ANALOG';
      NO_LOAD_CHECK='Both';
      NO_IO_CHECK='Both';
      NO_ASSERT_CHECK='TRUE';
      NO_DIR_CHECK='TRUE';
      ALLOW_CONNECT='TRUE';
  end_pin;
  body
    PART_NAME='3D01R5F-GP';
    BODY_NAME='3D01R5F-GP';
    PHYS_DES_PREFIX='R';
    CLASS='DISCRETE';
  end_body;
end_primitive;

END.
